# S9S_MB_2U (Grand Teton) — schematic netlist excerpt (pin names and nets, part order shuffled) for the footprints in the layout excerpt that follows; sources: Cadence DE-HDL packaged netlist, KiCad conversion of 03242023_DA0F0TMBIJ0_F0T_Motherboard_J_brd_V01_OCP.brd

J15  SCONN288_ADR50017P130CC  SCONN288_ADR50017-P130CC IO  pkg DDR288S_1-1VXB  page 96
  VIN_BULK0  = P12V_S3_AUX_CPU0_NVDIMM
  RFU0  = TP_CHH_CPU0_DIMM1_FRU_0
  VIN_MGMT  = P3V3_AUX
  HSCL  = I3C_SPD_DDREFGH_CPU0_LVC1_SCL_6
  HSDA  = I3C_SPD_DDREFGH_CPU0_LVC1_SDA
  VSS0  = GND
  DQ0_A  = M_H_CPU0_SA_DQ<0>
  VSS1  = GND
  DQ1_A  = M_H_CPU0_SA_DQ<1>
  VSS2  = GND
  DQS0_A_T  = M_H_CPU0_SA_DQS_DP<0>
  DQS0_A_C  = M_H_CPU0_SA_DQS_DN<0>
  VSS3  = GND
  DQ4_A  = M_H_CPU0_SA_DQ<4>
  VSS4  = GND
  DQ5_A  = M_H_CPU0_SA_DQ<5>
  VSS5  = GND
  DQ8_A  = M_H_CPU0_SA_DQ<8>
  VSS6  = GND
  DQ9_A  = M_H_CPU0_SA_DQ<9>
  VSS7  = GND
  DQS1_A_T  = M_H_CPU0_SA_DQS_DP<1>
  DQS1_A_C  = M_H_CPU0_SA_DQS_DN<1>
  VSS8  = GND
  DQ12_A  = M_H_CPU0_SA_DQ<12>
  VSS9  = GND
  DQ13_A  = M_H_CPU0_SA_DQ<13>
  VSS10  = GND
  DQ16_A  = M_H_CPU0_SA_DQ<16>
  VSS11  = GND
  DQ17_A  = M_H_CPU0_SA_DQ<17>
  VSS12  = GND
  DQS2_A_T  = M_H_CPU0_SA_DQS_DP<2>
  DQS2_A_C  = M_H_CPU0_SA_DQS_DN<2>
  VSS13  = GND
  DQ20_A  = M_H_CPU0_SA_DQ<20>
  VSS14  = GND
  DQ21_A  = M_H_CPU0_SA_DQ<21>
  VSS15  = GND
  DQ24_A  = M_H_CPU0_SA_DQ<24>
  VSS16  = GND
  DQ25_A  = M_H_CPU0_SA_DQ<25>
  VSS17  = GND
  DQS3_A_T  = M_H_CPU0_SA_DQS_DP<3>
  DQS3_A_C  = M_H_CPU0_SA_DQS_DN<3>
  VSS18  = GND
  DQ28_A  = M_H_CPU0_SA_DQ<28>
  VSS19  = GND
  DQ29_A  = M_H_CPU0_SA_DQ<29>
  VSS20  = GND
  CB0_A  = M_H_CPU0_SA_CB<0>
  VSS21  = GND
  CB1_A  = M_H_CPU0_SA_CB<1>
  VSS22  = GND
  DQS4_A_T  = M_H_CPU0_SA_DQS_DP<4>
  DQS4_A_C  = M_H_CPU0_SA_DQS_DN<4>
  VSS23  = GND
  CB4_A  = M_H_CPU0_SA_CB<4>
  VSS24  = GND
  CB5_A  = M_H_CPU0_SA_CB<5>
  VSS25  = GND
  ALERT_N  = M_H_CPU0_ALERT_N
  VSS26  = GND
  CS0_A_N  = M_H_CPU0_SA_CS_N<0>
  VSS27  = GND
  CA0_A  = M_H_CPU0_SA_CA<0>
  VSS28  = GND
  CA2_A  = M_H_CPU0_SA_CA<2>
  VSS29  = GND
  CA4_A  = M_H_CPU0_SA_CA<4>
  VSS30  = GND
  CA6_A  = M_H_CPU0_SA_CA<6>
  VSS31  = GND
  PAR_A  = M_H_CPU0_SA_PAR
  VSS32  = GND
  CA0_B  = M_H_CPU0_SB_CA<0>
  VSS33  = GND
  CA2_B  = M_H_CPU0_SB_CA<2>
  VSS34  = GND
  CA4_B  = M_H_CPU0_SB_CA<4>
  VSS35  = GND
  CA6_B  = M_H_CPU0_SB_CA<6>
  VSS36  = GND
  CS0_B_N  = M_H_CPU0_SB_CS_N<0>
  VSS37  = GND
  \lbd||rsp_a_n\  = M_H_CPU0_SA_RSP<0>
  \lbs||rsp_b_n\  = M_H_CPU0_SB_RSP<0>
  VSS38  = GND
  CB4_B  = M_H_CPU0_SB_CB<4>
  VSS39  = GND
  CB5_B  = M_H_CPU0_SB_CB<5>
  VSS40  = GND
  \dqs9_b_t||tdqs9_b_t||dbi4_b_n\  = M_H_CPU0_SB_DQS_DP<9>
  \dqs9_b_c||tdqs9_b_c\  = M_H_CPU0_SB_DQS_DN<9>
  VSS41  = GND
  CB0_B  = M_H_CPU0_SB_CB<0>
  VSS42  = GND
  CB1_B  = M_H_CPU0_SB_CB<1>
  VSS43  = GND
  DQ0_B  = M_H_CPU0_SB_DQ<0>
  VSS44  = GND
  DQ1_B  = M_H_CPU0_SB_DQ<1>
  VSS45  = GND
  DQS0_B_T  = M_H_CPU0_SB_DQS_DP<0>
  DQS0_B_C  = M_H_CPU0_SB_DQS_DN<0>
  VSS46  = GND
  DQ4_B  = M_H_CPU0_SB_DQ<4>
  VSS47  = GND
  DQ5_B  = M_H_CPU0_SB_DQ<5>
  VSS48  = GND
  DQ8_B  = M_H_CPU0_SB_DQ<8>
  VSS49  = GND
  DQ9_B  = M_H_CPU0_SB_DQ<9>
  VSS50  = GND
  DQS1_B_T  = M_H_CPU0_SB_DQS_DP<1>
  DQS1_B_C  = M_H_CPU0_SB_DQS_DN<1>
  VSS51  = GND
  DQ12_B  = M_H_CPU0_SB_DQ<12>
  VSS52  = GND
  DQ13_B  = M_H_CPU0_SB_DQ<13>
  VSS53  = GND
  DQ16_B  = M_H_CPU0_SB_DQ<16>
  VSS54  = GND
  DQ17_B  = M_H_CPU0_SB_DQ<17>
  VSS55  = GND
  DQS2_B_T  = M_H_CPU0_SB_DQS_DP<2>
  DQS2_B_C  = M_H_CPU0_SB_DQS_DN<2>
  VSS56  = GND
  DQ20_B  = M_H_CPU0_SB_DQ<20>
  VSS57  = GND
  DQ21_B  = M_H_CPU0_SB_DQ<21>
  VSS58  = GND
  DQ24_B  = M_H_CPU0_SB_DQ<24>
  VSS59  = GND
  DQ25_B  = M_H_CPU0_SB_DQ<25>
  VSS60  = GND
  DQS3_B_T  = M_H_CPU0_SB_DQS_DP<3>
  DQS3_B_C  = M_H_CPU0_SB_DQS_DN<3>
  VSS61  = GND
  DQ28_B  = M_H_CPU0_SB_DQ<28>
  VSS62  = GND
  DQ29_B  = M_H_CPU0_SB_DQ<29>
  VSS63  = GND
  RFU1  = TP_CHH_CPU0_DIMM1_FRU_1
  VIN_BULK1  = P12V_S3_AUX_CPU0_NVDIMM
  VIN_BULK2  = P12V_S3_AUX_CPU0_NVDIMM
  \pwr_good||fail_n\  = PWRGD_CHH_CPU0_DIMM1
  HSA  = PD_CHH_CPU0_DIMM1_SAA
  RFU2  = TP_CHH_CPU0_DIMM1_FRU_2
  RFU3  = TP_CHH_CPU0_DIMM1_FRU_3
  VSS64  = GND
  DQ2_A  = M_H_CPU0_SA_DQ<2>
  VSS65  = GND
  DQ3_A  = M_H_CPU0_SA_DQ<3>
  VSS66  = GND
  \dqs5_a_c||tdqs5_a_c||dqs5_a_t||tdqs5_a_t\  = M_H_CPU0_SA_DQS_DN<5>
  \dqs5_a_t||tdqs5_a_t\  = M_H_CPU0_SA_DQS_DP<5>
  VSS67  = GND
  DQ6_A  = M_H_CPU0_SA_DQ<6>
  VSS68  = GND
  DQ7_A  = M_H_CPU0_SA_DQ<7>
  VSS69  = GND
  DQ10_A  = M_H_CPU0_SA_DQ<10>
  VSS70  = GND
  DQ11_A  = M_H_CPU0_SA_DQ<11>
  VSS71  = GND
  \dqs6_a_c||tdqs6_a_c||dqs6_a_t||tdqs6_a_t\  = M_H_CPU0_SA_DQS_DN<6>
  \dqs6_a_t||tdqs6_a_t\  = M_H_CPU0_SA_DQS_DP<6>
  VSS72  = GND
  DQ14_A  = M_H_CPU0_SA_DQ<14>
  VSS73  = GND
  DQ15_A  = M_H_CPU0_SA_DQ<15>
  VSS74  = GND
  DQ18_A  = M_H_CPU0_SA_DQ<18>
  VSS75  = GND
  DQ19_A  = M_H_CPU0_SA_DQ<19>
  VSS76  = GND
  \dqs7_a_c||tdqs7_a_c\  = M_H_CPU0_SA_DQS_DN<7>
  \dqs7_a_t||tdqs7_a_t\  = M_H_CPU0_SA_DQS_DP<7>
  VSS77  = GND
  DQ22_A  = M_H_CPU0_SA_DQ<22>
  VSS78  = GND
  DQ23_A  = M_H_CPU0_SA_DQ<23>
  VSS79  = GND
  DQ26_A  = M_H_CPU0_SA_DQ<26>
  VSS80  = GND
  DQ27_A  = M_H_CPU0_SA_DQ<27>
  VSS81  = GND
  \dqs8_a_c||tdqs8_a_c\  = M_H_CPU0_SA_DQS_DN<8>
  \dqs8_a_t||tdqs8_a_t\  = M_H_CPU0_SA_DQS_DP<8>
  VSS82  = GND
  DQ30_A  = M_H_CPU0_SA_DQ<30>
  VSS83  = GND
  DQ31_A  = M_H_CPU0_SA_DQ<31>
  VSS84  = GND
  CB2_A  = M_H_CPU0_SA_CB<2>
  VSS85  = GND
  CB3_A  = M_H_CPU0_SA_CB<3>
  VSS86  = GND
  \dqs9_a_c||tdqs9_a_c\  = M_H_CPU0_SA_DQS_DN<9>
  \dqs9_a_t||tdqs9_a_t\  = M_H_CPU0_SA_DQS_DP<9>
  VSS87  = GND
  CB6_A  = M_H_CPU0_SA_CB<6>
  VSS88  = GND
  CB7_A  = M_H_CPU0_SA_CB<7>
  VSS89  = GND
  RESET_N  = RST_M_GH_CPU0_FPGA_N
  VSS90  = GND
  CS1_A_N  = M_H_CPU0_SA_CS_N<1>
  VSS91  = GND
  CA1_A  = M_H_CPU0_SA_CA<1>
  VSS92  = GND
  CA3_A  = M_H_CPU0_SA_CA<3>
  VSS93  = GND
  CA5_A  = M_H_CPU0_SA_CA<5>
  VSS94  = GND
  CK_T  = M_H_CPU0_CLK_DP<0>
  CK_C  = M_H_CPU0_CLK_DN<0>
  VSS95  = GND
  RFU4  = TP_CHH_CPU0_DIMM1_FRU_4
  CA1_B  = M_H_CPU0_SB_CA<1>
  VSS96  = GND
  CA3_B  = M_H_CPU0_SB_CA<3>
  VSS97  = GND
  CA5_B  = M_H_CPU0_SB_CA<5>
  VSS98  = GND
  PAR_B  = M_H_CPU0_SB_PAR
  VSS99  = GND
  CS1_B_N  = M_H_CPU0_SB_CS_N<1>
  VSS100  = GND
  RFU5  = TP_CHH_CPU0_DIMM1_FRU_5
  RFU6  = TP_CHH_CPU0_DIMM1_FRU_6
  VSS101  = GND
  CB6_B  = M_H_CPU0_SB_CB<6>
  VSS102  = GND
  CB7_B  = M_H_CPU0_SB_CB<7>
  VSS103  = GND
  DQS4_B_C  = M_H_CPU0_SB_DQS_DN<4>
  DQS4_B_T  = M_H_CPU0_SB_DQS_DP<4>
  VSS104  = GND
  CB2_B  = M_H_CPU0_SB_CB<2>
  VSS105  = GND
  CB3_B  = M_H_CPU0_SB_CB<3>
  VSS106  = GND
  DQ2_B  = M_H_CPU0_SB_DQ<2>
  VSS107  = GND
  DQ3_B  = M_H_CPU0_SB_DQ<3>
  VSS108  = GND
  \dqs5_b_c||tdqs5_b_c\  = M_H_CPU0_SB_DQS_DN<5>
  \dqs5_b_t||tdqs5_b_t\  = M_H_CPU0_SB_DQS_DP<5>
  VSS109  = GND
  DQ6_B  = M_H_CPU0_SB_DQ<6>
  VSS110  = GND
  DQ7_B  = M_H_CPU0_SB_DQ<7>
  VSS111  = GND
  DQ10_B  = M_H_CPU0_SB_DQ<10>
  VSS112  = GND
  DQ11_B  = M_H_CPU0_SB_DQ<11>
  VSS113  = GND
  \dqs6_b_c||tdqs6_b_c\  = M_H_CPU0_SB_DQS_DN<6>
  \dqs6_b_t||tdqs6_b_t\  = M_H_CPU0_SB_DQS_DP<6>
  VSS114  = GND
  DQ14_B  = M_H_CPU0_SB_DQ<14>
  VSS115  = GND
  DQ15_B  = M_H_CPU0_SB_DQ<15>
  VSS116  = GND
  DQ18_B  = M_H_CPU0_SB_DQ<18>
  VSS117  = GND
  DQ19_B  = M_H_CPU0_SB_DQ<19>
  VSS118  = GND
  \dqs7_b_c||tdqs7_b_c\  = M_H_CPU0_SB_DQS_DN<7>
  \dqs7_b_t||tdqs7_b_t\  = M_H_CPU0_SB_DQS_DP<7>
  VSS119  = GND
  DQ22_B  = M_H_CPU0_SB_DQ<22>
  VSS120  = GND
  DQ23_B  = M_H_CPU0_SB_DQ<23>
  VSS121  = GND
  DQ26_B  = M_H_CPU0_SB_DQ<26>
  VSS122  = GND
  DQ27_B  = M_H_CPU0_SB_DQ<27>
  VSS123  = GND
  \dqs8_b_c||tdqs8_b_c\  = M_H_CPU0_SB_DQS_DN<8>
  \dqs8_b_t||tdqs8_b_t\  = M_H_CPU0_SB_DQS_DP<8>
  VSS124  = GND
  DQ30_B  = M_H_CPU0_SB_DQ<30>
  VSS125  = GND
  DQ31_B  = M_H_CPU0_SB_DQ<31>
  VSS126  = GND
  G1  = GND
  G2  = GND
  G3  = GND

(kicad_pcb
	(version 20260206)
	(generator "pcbnew")
	(generator_version "10.0")
	(general
		(thickness 1.6)
		(legacy_teardrops no)
	)
	(paper "A4")
	(title_block
		(title "03242023_DA0F0TMBIJ0_F0T_Motherboard_J_brd_V01_OCP.brd")
		(comment 1 "Grand Teton / footprint 2194 of 6105 (J15), pads 1-45 of 291")
	)
	(layers
		(0 "F.Cu" signal "TOP")
		(4 "In1.Cu" signal "GND")
		(6 "In2.Cu" signal "IN1")
		(8 "In3.Cu" signal "GND1")
		(10 "In4.Cu" signal "IN2")
		(12 "In5.Cu" signal "GND2")
		(14 "In6.Cu" signal "IN3")
		(16 "In7.Cu" signal "GND3")
		(18 "In8.Cu" signal "VCC")
		(20 "In9.Cu" signal "VCC1")
		(22 "In10.Cu" signal "GND4")
		(24 "In11.Cu" signal "IN4")
		(26 "In12.Cu" signal "GND5")
		(28 "In13.Cu" signal "IN5")
		(30 "In14.Cu" signal "GND6")
		(32 "In15.Cu" signal "IN6")
		(34 "In16.Cu" signal "GND7")
		(2 "B.Cu" signal "BOTTOM")
		(9 "F.Adhes" user "F.Adhesive")
		(11 "B.Adhes" user "B.Adhesive")
		(13 "F.Paste" user "Package Geometry/Pastemask Top")
		(15 "B.Paste" user "Package Geometry/Pastemask Bottom")
		(5 "F.SilkS" user "Ref Des/Silkscreen Top")
		(7 "B.SilkS" user "Ref Des/Silkscreen Bottom")
		(1 "F.Mask" user "Board Geometry/Soldermask Top")
		(3 "B.Mask" user "Board Geometry/Soldermask Bottom")
		(17 "Dwgs.User" user "User.Drawings")
		(19 "Cmts.User" user "User.Comments")
		(21 "Eco1.User" user "User.Eco1")
		(23 "Eco2.User" user "User.Eco2")
		(25 "Edge.Cuts" user "Board Geometry/Outline")
		(27 "Margin" user)
		(31 "F.CrtYd" user "Package Geometry/Place Bound Top")
		(29 "B.CrtYd" user "Package Geometry/Place Bound Bottom")
		(35 "F.Fab" user "Ref Des/Assembly Top")
		(33 "B.Fab" user "Ref Des/Assembly Bottom")
	)
	(footprint ""
		(layer "F.Cu")
		(at 461.609948 -258.091686)
		(property "Reference" "J15"
			(at 3.019552 -81.652872 0)
			(unlocked yes)
			(layer "F.SilkS")
			(effects
				(font
					(size 0.7874 0.5842)
					(thickness 0.1524)
				)
				(justify left)
			)
		)
		(property "Value" ""
			(at 0 0 0)
			(layer "F.Fab")
			(effects
				(font
					(size 1.27 1.27)
				)
			)
		)
		(duplicate_pad_numbers_are_jumpers no)
		(pad "1" smd rect
			(at -2.050034 -63.324994 270)
			(size 0.519938 1.4986)
			(layers "F.Cu" "F.Mask" "F.Paste")
			(net "P12V_S3_AUX_CPU0_NVDIMM")
		)
		(pad "2" smd rect
			(at -2.050034 -62.47511 270)
			(size 0.519938 1.4986)
			(layers "F.Cu" "F.Mask" "F.Paste")
			(net "TP_CHH_CPU0_DIMM1_FRU_0")
		)
		(pad "3" smd rect
			(at -2.050034 -61.624972 270)
			(size 0.519938 1.4986)
			(layers "F.Cu" "F.Mask" "F.Paste")
			(net "P3V3_AUX")
		)
		(pad "4" smd rect
			(at -2.050034 -60.775088 270)
			(size 0.519938 1.4986)
			(layers "F.Cu" "F.Mask" "F.Paste")
			(net "I3C_SPD_DDREFGH_CPU0_LVC1_SCL_6")
		)
		(pad "5" smd rect
			(at -2.050034 -59.92495 270)
			(size 0.519938 1.4986)
			(layers "F.Cu" "F.Mask" "F.Paste")
			(net "I3C_SPD_DDREFGH_CPU0_LVC1_SDA")
		)
		(pad "6" smd rect
			(at -2.050034 -59.075066 270)
			(size 0.519938 1.4986)
			(layers "F.Cu" "F.Mask" "F.Paste")
			(net "GND")
		)
		(pad "7" smd rect
			(at -2.050034 -58.224928 270)
			(size 0.519938 1.4986)
			(layers "F.Cu" "F.Mask" "F.Paste")
			(net "M_H_CPU0_SA_DQ<0>")
		)
		(pad "8" smd rect
			(at -2.050034 -57.375044 270)
			(size 0.519938 1.4986)
			(layers "F.Cu" "F.Mask" "F.Paste")
			(net "GND")
		)
		(pad "9" smd rect
			(at -2.050034 -56.524906 270)
			(size 0.519938 1.4986)
			(layers "F.Cu" "F.Mask" "F.Paste")
			(net "M_H_CPU0_SA_DQ<1>")
		)
		(pad "10" smd rect
			(at -2.050034 -55.675022 270)
			(size 0.519938 1.4986)
			(layers "F.Cu" "F.Mask" "F.Paste")
			(net "GND")
		)
		(pad "11" smd rect
			(at -2.050034 -54.824884 270)
			(size 0.519938 1.4986)
			(layers "F.Cu" "F.Mask" "F.Paste")
			(net "M_H_CPU0_SA_DQS_DP<0>")
		)
		(pad "12" smd rect
			(at -2.050034 -53.975 270)
			(size 0.519938 1.4986)
			(layers "F.Cu" "F.Mask" "F.Paste")
			(net "M_H_CPU0_SA_DQS_DN<0>")
		)
		(pad "13" smd rect
			(at -2.050034 -53.125116 270)
			(size 0.519938 1.4986)
			(layers "F.Cu" "F.Mask" "F.Paste")
			(net "GND")
		)
		(pad "14" smd rect
			(at -2.050034 -52.274978 270)
			(size 0.519938 1.4986)
			(layers "F.Cu" "F.Mask" "F.Paste")
			(net "M_H_CPU0_SA_DQ<4>")
		)
		(pad "15" smd rect
			(at -2.050034 -51.425094 270)
			(size 0.519938 1.4986)
			(layers "F.Cu" "F.Mask" "F.Paste")
			(net "GND")
		)
		(pad "16" smd rect
			(at -2.050034 -50.574956 270)
			(size 0.519938 1.4986)
			(layers "F.Cu" "F.Mask" "F.Paste")
			(net "M_H_CPU0_SA_DQ<5>")
		)
		(pad "17" smd rect
			(at -2.050034 -49.725072 270)
			(size 0.519938 1.4986)
			(layers "F.Cu" "F.Mask" "F.Paste")
			(net "GND")
		)
		(pad "18" smd rect
			(at -2.050034 -48.874934 270)
			(size 0.519938 1.4986)
			(layers "F.Cu" "F.Mask" "F.Paste")
			(net "M_H_CPU0_SA_DQ<8>")
		)
		(pad "19" smd rect
			(at -2.050034 -48.02505 270)
			(size 0.519938 1.4986)
			(layers "F.Cu" "F.Mask" "F.Paste")
			(net "GND")
		)
		(pad "20" smd rect
			(at -2.050034 -47.174912 270)
			(size 0.519938 1.4986)
			(layers "F.Cu" "F.Mask" "F.Paste")
			(net "M_H_CPU0_SA_DQ<9>")
		)
		(pad "21" smd rect
			(at -2.050034 -46.325028 270)
			(size 0.519938 1.4986)
			(layers "F.Cu" "F.Mask" "F.Paste")
			(net "GND")
		)
		(pad "22" smd rect
			(at -2.050034 -45.47489 270)
			(size 0.519938 1.4986)
			(layers "F.Cu" "F.Mask" "F.Paste")
			(net "M_H_CPU0_SA_DQS_DP<1>")
		)
		(pad "23" smd rect
			(at -2.050034 -44.625006 270)
			(size 0.519938 1.4986)
			(layers "F.Cu" "F.Mask" "F.Paste")
			(net "M_H_CPU0_SA_DQS_DN<1>")
		)
		(pad "24" smd rect
			(at -2.050034 -43.775122 270)
			(size 0.519938 1.4986)
			(layers "F.Cu" "F.Mask" "F.Paste")
			(net "GND")
		)
		(pad "25" smd rect
			(at -2.050034 -42.924984 270)
			(size 0.519938 1.4986)
			(layers "F.Cu" "F.Mask" "F.Paste")
			(net "M_H_CPU0_SA_DQ<12>")
		)
		(pad "26" smd rect
			(at -2.050034 -42.0751 270)
			(size 0.519938 1.4986)
			(layers "F.Cu" "F.Mask" "F.Paste")
			(net "GND")
		)
		(pad "27" smd rect
			(at -2.050034 -41.224962 270)
			(size 0.519938 1.4986)
			(layers "F.Cu" "F.Mask" "F.Paste")
			(net "M_H_CPU0_SA_DQ<13>")
		)
		(pad "28" smd rect
			(at -2.050034 -40.375078 270)
			(size 0.519938 1.4986)
			(layers "F.Cu" "F.Mask" "F.Paste")
			(net "GND")
		)
		(pad "29" smd rect
			(at -2.050034 -39.52494 270)
			(size 0.519938 1.4986)
			(layers "F.Cu" "F.Mask" "F.Paste")
			(net "M_H_CPU0_SA_DQ<16>")
		)
		(pad "30" smd rect
			(at -2.050034 -38.675056 270)
			(size 0.519938 1.4986)
			(layers "F.Cu" "F.Mask" "F.Paste")
			(net "GND")
		)
		(pad "31" smd rect
			(at -2.050034 -37.824918 270)
			(size 0.519938 1.4986)
			(layers "F.Cu" "F.Mask" "F.Paste")
			(net "M_H_CPU0_SA_DQ<17>")
		)
		(pad "32" smd rect
			(at -2.050034 -36.975034 270)
			(size 0.519938 1.4986)
			(layers "F.Cu" "F.Mask" "F.Paste")
			(net "GND")
		)
		(pad "33" smd rect
			(at -2.050034 -36.124896 270)
			(size 0.519938 1.4986)
			(layers "F.Cu" "F.Mask" "F.Paste")
			(net "M_H_CPU0_SA_DQS_DP<2>")
		)
		(pad "34" smd rect
			(at -2.050034 -35.275012 270)
			(size 0.519938 1.4986)
			(layers "F.Cu" "F.Mask" "F.Paste")
			(net "M_H_CPU0_SA_DQS_DN<2>")
		)
		(pad "35" smd rect
			(at -2.050034 -34.425128 270)
			(size 0.519938 1.4986)
			(layers "F.Cu" "F.Mask" "F.Paste")
			(net "GND")
		)
		(pad "36" smd rect
			(at -2.050034 -33.57499 270)
			(size 0.519938 1.4986)
			(layers "F.Cu" "F.Mask" "F.Paste")
			(net "M_H_CPU0_SA_DQ<20>")
		)
		(pad "37" smd rect
			(at -2.050034 -32.725106 270)
			(size 0.519938 1.4986)
			(layers "F.Cu" "F.Mask" "F.Paste")
			(net "GND")
		)
		(pad "38" smd rect
			(at -2.050034 -31.874968 270)
			(size 0.519938 1.4986)
			(layers "F.Cu" "F.Mask" "F.Paste")
			(net "M_H_CPU0_SA_DQ<21>")
		)
		(pad "39" smd rect
			(at -2.050034 -31.025084 270)
			(size 0.519938 1.4986)
			(layers "F.Cu" "F.Mask" "F.Paste")
			(net "GND")
		)
		(pad "40" smd rect
			(at -2.050034 -30.174946 270)
			(size 0.519938 1.4986)
			(layers "F.Cu" "F.Mask" "F.Paste")
			(net "M_H_CPU0_SA_DQ<24>")
		)
		(pad "41" smd rect
			(at -2.050034 -29.325062 270)
			(size 0.519938 1.4986)
			(layers "F.Cu" "F.Mask" "F.Paste")
			(net "GND")
		)
		(pad "42" smd rect
			(at -2.050034 -28.474924 270)
			(size 0.519938 1.4986)
			(layers "F.Cu" "F.Mask" "F.Paste")
			(net "M_H_CPU0_SA_DQ<25>")
		)
		(pad "43" smd rect
			(at -2.050034 -27.62504 270)
			(size 0.519938 1.4986)
			(layers "F.Cu" "F.Mask" "F.Paste")
			(net "GND")
		)
		(pad "44" smd rect
			(at -2.050034 -26.774902 270)
			(size 0.519938 1.4986)
			(layers "F.Cu" "F.Mask" "F.Paste")
			(net "M_H_CPU0_SA_DQS_DP<3>")
		)
		(pad "45" smd rect
			(at -2.050034 -25.925018 270)
			(size 0.519938 1.4986)
			(layers "F.Cu" "F.Mask" "F.Paste")
			(net "M_H_CPU0_SA_DQS_DN<3>")
		)
	)
)
